(kicad_pcb
	(version 20260206)
	(generator "pcbnew")
	(generator_version "10.0")
	(general
		(thickness 1.6)
		(legacy_teardrops no)
	)
	(paper "A4")
	(title_block
		(title "04192023_DAF0TMB3IC0_F0TG_MB_C_brd_V02_OCP.brd")
		(comment 1 "Grand Teton / footprints 7979-7986 of 8354")
	)
	(layers
		(0 "F.Cu" signal "TOP")
		(4 "In1.Cu" signal "GND")
		(6 "In2.Cu" signal "IN1")
		(8 "In3.Cu" signal "GND1")
		(10 "In4.Cu" signal "IN2")
		(12 "In5.Cu" signal "GND2")
		(14 "In6.Cu" signal "IN3")
		(16 "In7.Cu" signal "GND3")
		(18 "In8.Cu" signal "VCC")
		(20 "In9.Cu" signal "VCC1")
		(22 "In10.Cu" signal "GND4")
		(24 "In11.Cu" signal "IN4")
		(26 "In12.Cu" signal "GND5")
		(28 "In13.Cu" signal "IN5")
		(30 "In14.Cu" signal "GND6")
		(32 "In15.Cu" signal "IN6")
		(34 "In16.Cu" signal "GND7")
		(2 "B.Cu" signal "BOTTOM")
		(9 "F.Adhes" user "F.Adhesive")
		(11 "B.Adhes" user "B.Adhesive")
		(13 "F.Paste" user "Package Geometry/Pastemask Top")
		(15 "B.Paste" user "Package Geometry/Pastemask Bottom")
		(5 "F.SilkS" user "Ref Des/Silkscreen Top")
		(7 "B.SilkS" user "Ref Des/Silkscreen Bottom")
		(1 "F.Mask" user "Board Geometry/Soldermask Top")
		(3 "B.Mask" user "Board Geometry/Soldermask Bottom")
		(17 "Dwgs.User" user "User.Drawings")
		(19 "Cmts.User" user "User.Comments")
		(21 "Eco1.User" user "User.Eco1")
		(23 "Eco2.User" user "User.Eco2")
		(25 "Edge.Cuts" user "Board Geometry/Outline")
		(27 "Margin" user)
		(31 "F.CrtYd" user "Package Geometry/Place Bound Top")
		(29 "B.CrtYd" user "Package Geometry/Place Bound Bottom")
		(35 "F.Fab" user "Ref Des/Assembly Top")
		(33 "B.Fab" user "Ref Des/Assembly Bottom")
	)
	(footprint ""
		(layer "B.Cu")
		(at 424.012106 -192.660016)
		(property "Reference" "C159"
			(at 0 0 0)
			(layer "B.SilkS")
			(hide yes)
			(effects
				(font
					(size 1.27 1.27)
				)
				(justify mirror)
			)
		)
		(property "Value" ""
			(at 0 0 0)
			(layer "B.Fab")
			(effects
				(font
					(size 1.27 1.27)
				)
				(justify mirror)
			)
		)
		(duplicate_pad_numbers_are_jumpers no)
		(fp_line
			(start -1.524 -0.762)
			(end -1.524 0.762)
			(stroke
				(width 0.1524)
				(type default)
			)
			(layer "B.SilkS")
		)
		(fp_line
			(start -1.524 0.762)
			(end 1.524 0.762)
			(stroke
				(width 0.1524)
				(type default)
			)
			(layer "B.SilkS")
		)
		(fp_line
			(start 1.524 -0.762)
			(end -1.524 -0.762)
			(stroke
				(width 0.1524)
				(type default)
			)
			(layer "B.SilkS")
		)
		(fp_line
			(start 1.524 0.762)
			(end 1.524 -0.762)
			(stroke
				(width 0.1524)
				(type default)
			)
			(layer "B.SilkS")
		)
		(fp_line
			(start -1.1049 -0.724916)
			(end 1.1049 -0.724916)
			(stroke
				(width 0.1)
				(type default)
			)
			(layer "B.Fab")
		)
		(fp_line
			(start -1.1049 0.724916)
			(end -1.1049 -0.724916)
			(stroke
				(width 0.1)
				(type default)
			)
			(layer "B.Fab")
		)
		(fp_line
			(start 1.1049 -0.724916)
			(end 1.1049 0.724916)
			(stroke
				(width 0.1)
				(type default)
			)
			(layer "B.Fab")
		)
		(fp_line
			(start 1.1049 0.724916)
			(end -1.1049 0.724916)
			(stroke
				(width 0.1)
				(type default)
			)
			(layer "B.Fab")
		)
		(pad "1" smd rect
			(at 0.889 0)
			(size 1.016 1.27)
			(layers "B.Cu" "B.Mask" "B.Paste")
			(net "P12V_MEM_CPU0")
		)
		(pad "2" smd rect
			(at -0.889 0)
			(size 1.016 1.27)
			(layers "B.Cu" "B.Mask" "B.Paste")
			(net "GND")
		)
	)
	(footprint ""
		(layer "B.Cu")
		(at 194.33413 -351.23882 90)
		(property "Reference" "PC514_2"
			(at 0 0 90)
			(layer "B.SilkS")
			(hide yes)
			(effects
				(font
					(size 1.27 1.27)
				)
				(justify mirror)
			)
		)
		(property "Value" ""
			(at 0 0 90)
			(layer "B.Fab")
			(effects
				(font
					(size 1.27 1.27)
				)
				(justify mirror)
			)
		)
		(duplicate_pad_numbers_are_jumpers no)
		(fp_line
			(start 1.524 -0.762)
			(end -1.524 -0.762)
			(stroke
				(width 0.1524)
				(type default)
			)
			(layer "B.SilkS")
		)
		(fp_line
			(start -1.524 -0.762)
			(end -1.524 0.762)
			(stroke
				(width 0.1524)
				(type default)
			)
			(layer "B.SilkS")
		)
		(fp_line
			(start 1.524 0.762)
			(end 1.524 -0.762)
			(stroke
				(width 0.1524)
				(type default)
			)
			(layer "B.SilkS")
		)
		(fp_line
			(start -1.524 0.762)
			(end 1.524 0.762)
			(stroke
				(width 0.1524)
				(type default)
			)
			(layer "B.SilkS")
		)
		(fp_line
			(start 1.1049 -0.724916)
			(end 1.1049 0.724916)
			(stroke
				(width 0.1)
				(type default)
			)
			(layer "B.Fab")
		)
		(fp_line
			(start -1.1049 -0.724916)
			(end 1.1049 -0.724916)
			(stroke
				(width 0.1)
				(type default)
			)
			(layer "B.Fab")
		)
		(fp_line
			(start 1.1049 0.724916)
			(end -1.1049 0.724916)
			(stroke
				(width 0.1)
				(type default)
			)
			(layer "B.Fab")
		)
		(fp_line
			(start -1.1049 0.724916)
			(end -1.1049 -0.724916)
			(stroke
				(width 0.1)
				(type default)
			)
			(layer "B.Fab")
		)
		(pad "1" smd rect
			(at 0.889 0 90)
			(size 1.016 1.27)
			(layers "B.Cu" "B.Mask" "B.Paste")
			(net "SW_P12V_AUX_PVDD11_S3_P1_FLT")
		)
		(pad "2" smd rect
			(at -0.889 0 90)
			(size 1.016 1.27)
			(layers "B.Cu" "B.Mask" "B.Paste")
			(net "GND")
		)
	)
	(footprint ""
		(layer "B.Cu")
		(at 217.678 -338.582 180)
		(property "Reference" "R6746"
			(at 0 0 0)
			(layer "B.SilkS")
			(hide yes)
			(effects
				(font
					(size 1.27 1.27)
				)
				(justify mirror)
			)
		)
		(property "Value" ""
			(at 0 0 0)
			(layer "B.Fab")
			(effects
				(font
					(size 1.27 1.27)
				)
				(justify mirror)
			)
		)
		(duplicate_pad_numbers_are_jumpers no)
		(fp_line
			(start 0.32512 0.175006)
			(end 0.32512 -0.175006)
			(stroke
				(width 0.1)
				(type default)
			)
			(layer "B.Fab")
		)
		(fp_line
			(start 0.32512 -0.175006)
			(end -0.32512 -0.175006)
			(stroke
				(width 0.1)
				(type default)
			)
			(layer "B.Fab")
		)
		(fp_line
			(start -0.32512 0.175006)
			(end 0.32512 0.175006)
			(stroke
				(width 0.1)
				(type default)
			)
			(layer "B.Fab")
		)
		(fp_line
			(start -0.32512 -0.175006)
			(end -0.32512 0.175006)
			(stroke
				(width 0.1)
				(type default)
			)
			(layer "B.Fab")
		)
		(pad "1" smd rect
			(at 0.2667 0)
			(size 0.3048 0.381)
			(layers "B.Cu" "B.Mask" "B.Paste")
			(net "SMB_RT_CPU1_P3_R_SDA")
		)
		(pad "2" smd rect
			(at -0.2667 0 180)
			(size 0.3048 0.381)
			(layers "B.Cu" "B.Mask" "B.Paste")
			(net "SMB_RT_CPU1_P3_SDA")
		)
	)
	(footprint ""
		(layer "B.Cu")
		(at 231.648 -340.741 -90)
		(property "Reference" "R6763"
			(at 0 0 90)
			(layer "B.SilkS")
			(hide yes)
			(effects
				(font
					(size 1.27 1.27)
				)
				(justify mirror)
			)
		)
		(property "Value" ""
			(at 0 0 90)
			(layer "B.Fab")
			(effects
				(font
					(size 1.27 1.27)
				)
				(justify mirror)
			)
		)
		(duplicate_pad_numbers_are_jumpers no)
		(fp_line
			(start -0.32512 0.175006)
			(end 0.32512 0.175006)
			(stroke
				(width 0.1)
				(type default)
			)
			(layer "B.Fab")
		)
		(fp_line
			(start 0.32512 0.175006)
			(end 0.32512 -0.175006)
			(stroke
				(width 0.1)
				(type default)
			)
			(layer "B.Fab")
		)
		(fp_line
			(start -0.32512 -0.175006)
			(end -0.32512 0.175006)
			(stroke
				(width 0.1)
				(type default)
			)
			(layer "B.Fab")
		)
		(fp_line
			(start 0.32512 -0.175006)
			(end -0.32512 -0.175006)
			(stroke
				(width 0.1)
				(type default)
			)
			(layer "B.Fab")
		)
		(pad "1" smd rect
			(at 0.2667 0 90)
			(size 0.3048 0.381)
			(layers "B.Cu" "B.Mask" "B.Paste")
			(net "P1V8_CPU0_RT_1D")
		)
		(pad "2" smd rect
			(at -0.2667 0 270)
			(size 0.3048 0.381)
			(layers "B.Cu" "B.Mask" "B.Paste")
			(net "SMB_RT_CPU0_P0_R_SCL")
		)
	)
	(footprint ""
		(layer "B.Cu")
		(at 409.018994 -398.942052 90)
		(property "Reference" "C976"
			(at 0 0 90)
			(layer "B.SilkS")
			(hide yes)
			(effects
				(font
					(size 1.27 1.27)
				)
				(justify mirror)
			)
		)
		(property "Value" ""
			(at 0 0 90)
			(layer "B.Fab")
			(effects
				(font
					(size 1.27 1.27)
				)
				(justify mirror)
			)
		)
		(duplicate_pad_numbers_are_jumpers no)
		(fp_line
			(start 0.7874 -0.4064)
			(end -0.7874 -0.4064)
			(stroke
				(width 0.1524)
				(type default)
			)
			(layer "B.SilkS")
		)
		(fp_line
			(start -0.7874 -0.4064)
			(end -0.7874 0.4064)
			(stroke
				(width 0.1524)
				(type default)
			)
			(layer "B.SilkS")
		)
		(fp_line
			(start 0.7874 0.4064)
			(end 0.7874 -0.4064)
			(stroke
				(width 0.1524)
				(type default)
			)
			(layer "B.SilkS")
		)
		(fp_line
			(start -0.7874 0.4064)
			(end 0.7874 0.4064)
			(stroke
				(width 0.1524)
				(type default)
			)
			(layer "B.SilkS")
		)
		(fp_line
			(start 0.67945 -0.305054)
			(end 0.12065 -0.305054)
			(stroke
				(width 0.1)
				(type default)
			)
			(layer "B.Fab")
		)
		(fp_line
			(start 0.12065 -0.305054)
			(end 0.12065 -0.2794)
			(stroke
				(width 0.1)
				(type default)
			)
			(layer "B.Fab")
		)
		(fp_line
			(start -0.12065 -0.3048)
			(end -0.67945 -0.3048)
			(stroke
				(width 0.1)
				(type default)
			)
			(layer "B.Fab")
		)
		(fp_line
			(start -0.67945 -0.3048)
			(end -0.67945 0.3048)
			(stroke
				(width 0.1)
				(type default)
			)
			(layer "B.Fab")
		)
		(fp_line
			(start 0.12065 -0.2794)
			(end -0.12065 -0.2794)
			(stroke
				(width 0.1)
				(type default)
			)
			(layer "B.Fab")
		)
		(fp_line
			(start -0.12065 -0.2794)
			(end -0.12065 -0.3048)
			(stroke
				(width 0.1)
				(type default)
			)
			(layer "B.Fab")
		)
		(fp_line
			(start 0.12065 0.2794)
			(end 0.12065 0.3048)
			(stroke
				(width 0.1)
				(type default)
			)
			(layer "B.Fab")
		)
		(fp_line
			(start -0.120396 0.2794)
			(end 0.12065 0.2794)
			(stroke
				(width 0.1)
				(type default)
			)
			(layer "B.Fab")
		)
		(fp_line
			(start 0.67945 0.3048)
			(end 0.67945 -0.305054)
			(stroke
				(width 0.1)
				(type default)
			)
			(layer "B.Fab")
		)
		(fp_line
			(start 0.12065 0.3048)
			(end 0.67945 0.3048)
			(stroke
				(width 0.1)
				(type default)
			)
			(layer "B.Fab")
		)
		(fp_line
			(start -0.120396 0.3048)
			(end -0.120396 0.2794)
			(stroke
				(width 0.1)
				(type default)
			)
			(layer "B.Fab")
		)
		(fp_line
			(start -0.67945 0.3048)
			(end -0.120396 0.3048)
			(stroke
				(width 0.1)
				(type default)
			)
			(layer "B.Fab")
		)
		(pad "1" smd circle
			(at 0.40005 0 270)
			(size 0 0)
			(layers "B.Cu" "B.Mask" "B.Paste")
			(net "P0V9_CPU0_RT_2D")
		)
		(pad "2" smd circle
			(at -0.40005 0 270)
			(size 0 0)
			(layers "B.Cu" "B.Mask" "B.Paste")
			(net "GND")
		)
	)
	(footprint ""
		(layer "B.Cu")
		(at 62.68847 -15.58036 90)
		(property "Reference" "R3208"
			(at 0 0 90)
			(layer "B.SilkS")
			(hide yes)
			(effects
				(font
					(size 1.27 1.27)
				)
				(justify mirror)
			)
		)
		(property "Value" ""
			(at 0 0 90)
			(layer "B.Fab")
			(effects
				(font
					(size 1.27 1.27)
				)
				(justify mirror)
			)
		)
		(duplicate_pad_numbers_are_jumpers no)
		(fp_line
			(start 0.7874 -0.4064)
			(end -0.7874 -0.4064)
			(stroke
				(width 0.1524)
				(type default)
			)
			(layer "B.SilkS")
		)
		(fp_line
			(start -0.7874 -0.4064)
			(end -0.7874 0.4064)
			(stroke
				(width 0.1524)
				(type default)
			)
			(layer "B.SilkS")
		)
		(fp_line
			(start 0.7874 0.4064)
			(end 0.7874 -0.4064)
			(stroke
				(width 0.1524)
				(type default)
			)
			(layer "B.SilkS")
		)
		(fp_line
			(start -0.7874 0.4064)
			(end 0.7874 0.4064)
			(stroke
				(width 0.1524)
				(type default)
			)
			(layer "B.SilkS")
		)
		(fp_line
			(start 0.67945 -0.305054)
			(end 0.12065 -0.305054)
			(stroke
				(width 0.1)
				(type default)
			)
			(layer "B.Fab")
		)
		(fp_line
			(start 0.12065 -0.305054)
			(end 0.12065 -0.2794)
			(stroke
				(width 0.1)
				(type default)
			)
			(layer "B.Fab")
		)
		(fp_line
			(start -0.12065 -0.3048)
			(end -0.67945 -0.3048)
			(stroke
				(width 0.1)
				(type default)
			)
			(layer "B.Fab")
		)
		(fp_line
			(start -0.67945 -0.3048)
			(end -0.67945 0.3048)
			(stroke
				(width 0.1)
				(type default)
			)
			(layer "B.Fab")
		)
		(fp_line
			(start 0.12065 -0.2794)
			(end -0.12065 -0.2794)
			(stroke
				(width 0.1)
				(type default)
			)
			(layer "B.Fab")
		)
		(fp_line
			(start -0.12065 -0.2794)
			(end -0.12065 -0.3048)
			(stroke
				(width 0.1)
				(type default)
			)
			(layer "B.Fab")
		)
		(fp_line
			(start 0.12065 0.2794)
			(end 0.12065 0.3048)
			(stroke
				(width 0.1)
				(type default)
			)
			(layer "B.Fab")
		)
		(fp_line
			(start -0.120396 0.2794)
			(end 0.12065 0.2794)
			(stroke
				(width 0.1)
				(type default)
			)
			(layer "B.Fab")
		)
		(fp_line
			(start 0.67945 0.3048)
			(end 0.67945 -0.305054)
			(stroke
				(width 0.1)
				(type default)
			)
			(layer "B.Fab")
		)
		(fp_line
			(start 0.12065 0.3048)
			(end 0.67945 0.3048)
			(stroke
				(width 0.1)
				(type default)
			)
			(layer "B.Fab")
		)
		(fp_line
			(start -0.120396 0.3048)
			(end -0.120396 0.2794)
			(stroke
				(width 0.1)
				(type default)
			)
			(layer "B.Fab")
		)
		(fp_line
			(start -0.67945 0.3048)
			(end -0.120396 0.3048)
			(stroke
				(width 0.1)
				(type default)
			)
			(layer "B.Fab")
		)
		(pad "1" smd circle
			(at 0.40005 0 270)
			(size 0 0)
			(layers "B.Cu" "B.Mask" "B.Paste")
			(net "OCP_V3_2_ISO_BIF0_EN")
		)
		(pad "2" smd circle
			(at -0.40005 0 270)
			(size 0 0)
			(layers "B.Cu" "B.Mask" "B.Paste")
			(net "GND")
		)
	)
	(footprint ""
		(layer "B.Cu")
		(at 421.333168 -352.174048 -90)
		(property "Reference" "PR131"
			(at 0 0 90)
			(layer "B.SilkS")
			(hide yes)
			(effects
				(font
					(size 1.27 1.27)
				)
				(justify mirror)
			)
		)
		(property "Value" ""
			(at 0 0 90)
			(layer "B.Fab")
			(effects
				(font
					(size 1.27 1.27)
				)
				(justify mirror)
			)
		)
		(duplicate_pad_numbers_are_jumpers no)
		(fp_line
			(start -0.7874 0.4064)
			(end 0.7874 0.4064)
			(stroke
				(width 0.1524)
				(type default)
			)
			(layer "B.SilkS")
		)
		(fp_line
			(start 0.7874 0.4064)
			(end 0.7874 -0.4064)
			(stroke
				(width 0.1524)
				(type default)
			)
			(layer "B.SilkS")
		)
		(fp_line
			(start -0.7874 -0.4064)
			(end -0.7874 0.4064)
			(stroke
				(width 0.1524)
				(type default)
			)
			(layer "B.SilkS")
		)
		(fp_line
			(start 0.7874 -0.4064)
			(end -0.7874 -0.4064)
			(stroke
				(width 0.1524)
				(type default)
			)
			(layer "B.SilkS")
		)
		(fp_line
			(start -0.67945 0.3048)
			(end -0.120396 0.3048)
			(stroke
				(width 0.1)
				(type default)
			)
			(layer "B.Fab")
		)
		(fp_line
			(start -0.120396 0.3048)
			(end -0.120396 0.2794)
			(stroke
				(width 0.1)
				(type default)
			)
			(layer "B.Fab")
		)
		(fp_line
			(start 0.12065 0.3048)
			(end 0.67945 0.3048)
			(stroke
				(width 0.1)
				(type default)
			)
			(layer "B.Fab")
		)
		(fp_line
			(start 0.67945 0.3048)
			(end 0.67945 -0.305054)
			(stroke
				(width 0.1)
				(type default)
			)
			(layer "B.Fab")
		)
		(fp_line
			(start -0.120396 0.2794)
			(end 0.12065 0.2794)
			(stroke
				(width 0.1)
				(type default)
			)
			(layer "B.Fab")
		)
		(fp_line
			(start 0.12065 0.2794)
			(end 0.12065 0.3048)
			(stroke
				(width 0.1)
				(type default)
			)
			(layer "B.Fab")
		)
		(fp_line
			(start -0.12065 -0.2794)
			(end -0.12065 -0.3048)
			(stroke
				(width 0.1)
				(type default)
			)
			(layer "B.Fab")
		)
		(fp_line
			(start 0.12065 -0.2794)
			(end -0.12065 -0.2794)
			(stroke
				(width 0.1)
				(type default)
			)
			(layer "B.Fab")
		)
		(fp_line
			(start -0.67945 -0.3048)
			(end -0.67945 0.3048)
			(stroke
				(width 0.1)
				(type default)
			)
			(layer "B.Fab")
		)
		(fp_line
			(start -0.12065 -0.3048)
			(end -0.67945 -0.3048)
			(stroke
				(width 0.1)
				(type default)
			)
			(layer "B.Fab")
		)
		(fp_line
			(start 0.12065 -0.305054)
			(end 0.12065 -0.2794)
			(stroke
				(width 0.1)
				(type default)
			)
			(layer "B.Fab")
		)
		(fp_line
			(start 0.67945 -0.305054)
			(end 0.12065 -0.305054)
			(stroke
				(width 0.1)
				(type default)
			)
			(layer "B.Fab")
		)
		(pad "1" smd circle
			(at 0.40005 0 90)
			(size 0 0)
			(layers "B.Cu" "B.Mask" "B.Paste")
			(net "PVDD11_S3_P0_PVCC")
		)
		(pad "2" smd circle
			(at -0.40005 0 90)
			(size 0 0)
			(layers "B.Cu" "B.Mask" "B.Paste")
			(net "PVDD11_S3_P0_VCC1")
		)
	)
	(footprint ""
		(layer "B.Cu")
		(at 388.537958 -202.612752 180)
		(property "Reference" "R29"
			(at 0 0 0)
			(layer "B.SilkS")
			(hide yes)
			(effects
				(font
					(size 1.27 1.27)
				)
				(justify mirror)
			)
		)
		(property "Value" ""
			(at 0 0 0)
			(layer "B.Fab")
			(effects
				(font
					(size 1.27 1.27)
				)
				(justify mirror)
			)
		)
		(duplicate_pad_numbers_are_jumpers no)
		(fp_line
			(start 0.7874 0.4064)
			(end 0.7874 -0.4064)
			(stroke
				(width 0.1524)
				(type default)
			)
			(layer "B.SilkS")
		)
		(fp_line
			(start 0.7874 -0.4064)
			(end -0.7874 -0.4064)
			(stroke
				(width 0.1524)
				(type default)
			)
			(layer "B.SilkS")
		)
		(fp_line
			(start -0.7874 0.4064)
			(end 0.7874 0.4064)
			(stroke
				(width 0.1524)
				(type default)
			)
			(layer "B.SilkS")
		)
		(fp_line
			(start -0.7874 -0.4064)
			(end -0.7874 0.4064)
			(stroke
				(width 0.1524)
				(type default)
			)
			(layer "B.SilkS")
		)
		(fp_line
			(start 0.67945 0.3048)
			(end 0.67945 -0.305054)
			(stroke
				(width 0.1)
				(type default)
			)
			(layer "B.Fab")
		)
		(fp_line
			(start 0.67945 -0.305054)
			(end 0.12065 -0.305054)
			(stroke
				(width 0.1)
				(type default)
			)
			(layer "B.Fab")
		)
		(fp_line
			(start 0.12065 0.3048)
			(end 0.67945 0.3048)
			(stroke
				(width 0.1)
				(type default)
			)
			(layer "B.Fab")
		)
		(fp_line
			(start 0.12065 0.2794)
			(end 0.12065 0.3048)
			(stroke
				(width 0.1)
				(type default)
			)
			(layer "B.Fab")
		)
		(fp_line
			(start 0.12065 -0.2794)
			(end -0.12065 -0.2794)
			(stroke
				(width 0.1)
				(type default)
			)
			(layer "B.Fab")
		)
		(fp_line
			(start 0.12065 -0.305054)
			(end 0.12065 -0.2794)
			(stroke
				(width 0.1)
				(type default)
			)
			(layer "B.Fab")
		)
		(fp_line
			(start -0.120396 0.3048)
			(end -0.120396 0.2794)
			(stroke
				(width 0.1)
				(type default)
			)
			(layer "B.Fab")
		)
		(fp_line
			(start -0.120396 0.2794)
			(end 0.12065 0.2794)
			(stroke
				(width 0.1)
				(type default)
			)
			(layer "B.Fab")
		)
		(fp_line
			(start -0.12065 -0.2794)
			(end -0.12065 -0.3048)
			(stroke
				(width 0.1)
				(type default)
			)
			(layer "B.Fab")
		)
		(fp_line
			(start -0.12065 -0.3048)
			(end -0.67945 -0.3048)
			(stroke
				(width 0.1)
				(type default)
			)
			(layer "B.Fab")
		)
		(fp_line
			(start -0.67945 0.3048)
			(end -0.120396 0.3048)
			(stroke
				(width 0.1)
				(type default)
			)
			(layer "B.Fab")
		)
		(fp_line
			(start -0.67945 -0.3048)
			(end -0.67945 0.3048)
			(stroke
				(width 0.1)
				(type default)
			)
			(layer "B.Fab")
		)
		(pad "1" smd circle
			(at 0.40005 0)
			(size 0 0)
			(layers "B.Cu" "B.Mask" "B.Paste")
			(net "SMB_CPU0_3_R_SCL")
		)
		(pad "2" smd circle
			(at -0.40005 0)
			(size 0 0)
			(layers "B.Cu" "B.Mask" "B.Paste")
			(net "SMB_CPU0_3_SCL")
		)
	)
)
